# S9S_MB_2U (Grand Teton) — schematic netlist excerpt (pin names and nets, part order shuffled) for the footprints in the layout excerpt that follows; sources: Cadence DE-HDL packaged netlist, KiCad conversion of 03242023_DA0F0TMBIJ0_F0T_Motherboard_J_brd_V01_OCP.brd

C621  Q_CAP  1UF 25V 10% EMPTY  pkg C0402  page 129 : A = RST_PLD_CPU0_DRAM_GH_N ; B = GND
PR4234  Q_RES  0 5% CHIP  pkg 0402LF  page 278 : A = NC_PVCCD_HV_CPU0_ACSP6 ; B = GND

(kicad_pcb
	(version 20260206)
	(generator "pcbnew")
	(generator_version "10.0")
	(general
		(thickness 1.6)
		(legacy_teardrops no)
	)
	(paper "A4")
	(title_block
		(title "03242023_DA0F0TMBIJ0_F0T_Motherboard_J_brd_V01_OCP.brd")
		(comment 1 "Grand Teton / footprints 5109-5110 of 6105")
	)
	(layers
		(0 "F.Cu" signal "TOP")
		(4 "In1.Cu" signal "GND")
		(6 "In2.Cu" signal "IN1")
		(8 "In3.Cu" signal "GND1")
		(10 "In4.Cu" signal "IN2")
		(12 "In5.Cu" signal "GND2")
		(14 "In6.Cu" signal "IN3")
		(16 "In7.Cu" signal "GND3")
		(18 "In8.Cu" signal "VCC")
		(20 "In9.Cu" signal "VCC1")
		(22 "In10.Cu" signal "GND4")
		(24 "In11.Cu" signal "IN4")
		(26 "In12.Cu" signal "GND5")
		(28 "In13.Cu" signal "IN5")
		(30 "In14.Cu" signal "GND6")
		(32 "In15.Cu" signal "IN6")
		(34 "In16.Cu" signal "GND7")
		(2 "B.Cu" signal "BOTTOM")
		(9 "F.Adhes" user "F.Adhesive")
		(11 "B.Adhes" user "B.Adhesive")
		(13 "F.Paste" user "Package Geometry/Pastemask Top")
		(15 "B.Paste" user "Package Geometry/Pastemask Bottom")
		(5 "F.SilkS" user "Ref Des/Silkscreen Top")
		(7 "B.SilkS" user "Ref Des/Silkscreen Bottom")
		(1 "F.Mask" user "Board Geometry/Soldermask Top")
		(3 "B.Mask" user "Board Geometry/Soldermask Bottom")
		(17 "Dwgs.User" user "User.Drawings")
		(19 "Cmts.User" user "User.Comments")
		(21 "Eco1.User" user "User.Eco1")
		(23 "Eco2.User" user "User.Eco2")
		(25 "Edge.Cuts" user "Board Geometry/Outline")
		(27 "Margin" user)
		(31 "F.CrtYd" user "Package Geometry/Place Bound Top")
		(29 "B.CrtYd" user "Package Geometry/Place Bound Bottom")
		(35 "F.Fab" user "Ref Des/Assembly Top")
		(33 "B.Fab" user "Ref Des/Assembly Bottom")
	)
	(footprint ""
		(layer "B.Cu")
		(at 431.72888 -124.932948 90)
		(property "Reference" "PR4234"
			(at 0 0 90)
			(layer "B.SilkS")
			(hide yes)
			(effects
				(font
					(size 1.27 1.27)
				)
				(justify mirror)
			)
		)
		(property "Value" ""
			(at 0 0 90)
			(layer "B.Fab")
			(effects
				(font
					(size 1.27 1.27)
				)
				(justify mirror)
			)
		)
		(duplicate_pad_numbers_are_jumpers no)
		(fp_line
			(start 0.7874 -0.4064)
			(end -0.7874 -0.4064)
			(stroke
				(width 0.1524)
				(type default)
			)
			(layer "B.SilkS")
		)
		(fp_line
			(start -0.7874 -0.4064)
			(end -0.7874 0.4064)
			(stroke
				(width 0.1524)
				(type default)
			)
			(layer "B.SilkS")
		)
		(fp_line
			(start 0.7874 0.4064)
			(end 0.7874 -0.4064)
			(stroke
				(width 0.1524)
				(type default)
			)
			(layer "B.SilkS")
		)
		(fp_line
			(start -0.7874 0.4064)
			(end 0.7874 0.4064)
			(stroke
				(width 0.1524)
				(type default)
			)
			(layer "B.SilkS")
		)
		(fp_line
			(start 0.67945 -0.305054)
			(end 0.12065 -0.305054)
			(stroke
				(width 0.1)
				(type default)
			)
			(layer "B.Fab")
		)
		(fp_line
			(start 0.12065 -0.305054)
			(end 0.12065 -0.2794)
			(stroke
				(width 0.1)
				(type default)
			)
			(layer "B.Fab")
		)
		(fp_line
			(start -0.12065 -0.3048)
			(end -0.67945 -0.3048)
			(stroke
				(width 0.1)
				(type default)
			)
			(layer "B.Fab")
		)
		(fp_line
			(start -0.67945 -0.3048)
			(end -0.67945 0.3048)
			(stroke
				(width 0.1)
				(type default)
			)
			(layer "B.Fab")
		)
		(fp_line
			(start 0.12065 -0.2794)
			(end -0.12065 -0.2794)
			(stroke
				(width 0.1)
				(type default)
			)
			(layer "B.Fab")
		)
		(fp_line
			(start -0.12065 -0.2794)
			(end -0.12065 -0.3048)
			(stroke
				(width 0.1)
				(type default)
			)
			(layer "B.Fab")
		)
		(fp_line
			(start 0.12065 0.2794)
			(end 0.12065 0.3048)
			(stroke
				(width 0.1)
				(type default)
			)
			(layer "B.Fab")
		)
		(fp_line
			(start -0.120396 0.2794)
			(end 0.12065 0.2794)
			(stroke
				(width 0.1)
				(type default)
			)
			(layer "B.Fab")
		)
		(fp_line
			(start 0.67945 0.3048)
			(end 0.67945 -0.305054)
			(stroke
				(width 0.1)
				(type default)
			)
			(layer "B.Fab")
		)
		(fp_line
			(start 0.12065 0.3048)
			(end 0.67945 0.3048)
			(stroke
				(width 0.1)
				(type default)
			)
			(layer "B.Fab")
		)
		(fp_line
			(start -0.120396 0.3048)
			(end -0.120396 0.2794)
			(stroke
				(width 0.1)
				(type default)
			)
			(layer "B.Fab")
		)
		(fp_line
			(start -0.67945 0.3048)
			(end -0.120396 0.3048)
			(stroke
				(width 0.1)
				(type default)
			)
			(layer "B.Fab")
		)
		(pad "1" smd circle
			(at 0.40005 0 270)
			(size 0 0)
			(layers "B.Cu" "B.Mask" "B.Paste")
			(net "NC_PVCCD_HV_CPU0_ACSP6")
		)
		(pad "2" smd circle
			(at -0.40005 0 270)
			(size 0 0)
			(layers "B.Cu" "B.Mask" "B.Paste")
			(net "GND")
		)
	)
	(footprint ""
		(layer "B.Cu")
		(at 432.523392 -193.565272 -90)
		(property "Reference" "C621"
			(at 0 0 90)
			(layer "B.SilkS")
			(hide yes)
			(effects
				(font
					(size 1.27 1.27)
				)
				(justify mirror)
			)
		)
		(property "Value" ""
			(at 0 0 90)
			(layer "B.Fab")
			(effects
				(font
					(size 1.27 1.27)
				)
				(justify mirror)
			)
		)
		(duplicate_pad_numbers_are_jumpers no)
		(fp_line
			(start -0.7874 0.4064)
			(end 0.7874 0.4064)
			(stroke
				(width 0.1524)
				(type default)
			)
			(layer "B.SilkS")
		)
		(fp_line
			(start 0.7874 0.4064)
			(end 0.7874 -0.4064)
			(stroke
				(width 0.1524)
				(type default)
			)
			(layer "B.SilkS")
		)
		(fp_line
			(start -0.7874 -0.4064)
			(end -0.7874 0.4064)
			(stroke
				(width 0.1524)
				(type default)
			)
			(layer "B.SilkS")
		)
		(fp_line
			(start 0.7874 -0.4064)
			(end -0.7874 -0.4064)
			(stroke
				(width 0.1524)
				(type default)
			)
			(layer "B.SilkS")
		)
		(fp_line
			(start -0.67945 0.3048)
			(end -0.120396 0.3048)
			(stroke
				(width 0.1)
				(type default)
			)
			(layer "B.Fab")
		)
		(fp_line
			(start -0.120396 0.3048)
			(end -0.120396 0.2794)
			(stroke
				(width 0.1)
				(type default)
			)
			(layer "B.Fab")
		)
		(fp_line
			(start 0.12065 0.3048)
			(end 0.67945 0.3048)
			(stroke
				(width 0.1)
				(type default)
			)
			(layer "B.Fab")
		)
		(fp_line
			(start 0.67945 0.3048)
			(end 0.67945 -0.305054)
			(stroke
				(width 0.1)
				(type default)
			)
			(layer "B.Fab")
		)
		(fp_line
			(start -0.120396 0.2794)
			(end 0.12065 0.2794)
			(stroke
				(width 0.1)
				(type default)
			)
			(layer "B.Fab")
		)
		(fp_line
			(start 0.12065 0.2794)
			(end 0.12065 0.3048)
			(stroke
				(width 0.1)
				(type default)
			)
			(layer "B.Fab")
		)
		(fp_line
			(start -0.12065 -0.2794)
			(end -0.12065 -0.3048)
			(stroke
				(width 0.1)
				(type default)
			)
			(layer "B.Fab")
		)
		(fp_line
			(start 0.12065 -0.2794)
			(end -0.12065 -0.2794)
			(stroke
				(width 0.1)
				(type default)
			)
			(layer "B.Fab")
		)
		(fp_line
			(start -0.67945 -0.3048)
			(end -0.67945 0.3048)
			(stroke
				(width 0.1)
				(type default)
			)
			(layer "B.Fab")
		)
		(fp_line
			(start -0.12065 -0.3048)
			(end -0.67945 -0.3048)
			(stroke
				(width 0.1)
				(type default)
			)
			(layer "B.Fab")
		)
		(fp_line
			(start 0.12065 -0.305054)
			(end 0.12065 -0.2794)
			(stroke
				(width 0.1)
				(type default)
			)
			(layer "B.Fab")
		)
		(fp_line
			(start 0.67945 -0.305054)
			(end 0.12065 -0.305054)
			(stroke
				(width 0.1)
				(type default)
			)
			(layer "B.Fab")
		)
		(pad "1" smd circle
			(at 0.40005 0 90)
			(size 0 0)
			(layers "B.Cu" "B.Mask" "B.Paste")
			(net "RST_PLD_CPU0_DRAM_GH_N")
		)
		(pad "2" smd circle
			(at -0.40005 0 90)
			(size 0 0)
			(layers "B.Cu" "B.Mask" "B.Paste")
			(net "GND")
		)
	)
)
